# BASEBOARD_FAB2 (Tioga Pass) — schematic netlist excerpt (pin names and nets, part order shuffled) for the footprints in the layout excerpt that follows; sources: Cadence DE-HDL packaged netlist, KiCad conversion of Wiwynn_Tioga_Pass_MB.brd

R10W7  RES  4.75K 1% CHIP  pkg 0402  page 251 : A = P3V3_STBY ; B = PUMP_TACH1
R2L16  RES  22.1 1.0% CHIP  pkg 0402  page 235 : A = PWRGD_PVNN_PCH_R ; B = PWRGD_PVNN_P1V05_PCH
R9A9  RES  100.0 1% CHIP  pkg 0402  page 175 : A = RST_SYSTEM_BTN_BUF_N ; B = RST_SYSTEM_BTN_N

(kicad_pcb
	(version 20260206)
	(generator "pcbnew")
	(generator_version "10.0")
	(general
		(thickness 1.6)
		(legacy_teardrops no)
	)
	(paper "A4")
	(title_block
		(title "Wiwynn_Tioga_Pass_MB.brd")
		(comment 1 "Tioga Pass / footprints 1472-1474 of 4770")
	)
	(layers
		(0 "F.Cu" signal "TOP")
		(4 "In1.Cu" signal "L2GND")
		(6 "In2.Cu" signal "L3")
		(8 "In3.Cu" signal "L4GND")
		(10 "In4.Cu" signal "L5")
		(12 "In5.Cu" signal "L6GND")
		(14 "In6.Cu" signal "L7VCC")
		(16 "In7.Cu" signal "L8VCC")
		(18 "In8.Cu" signal "L9GND")
		(20 "In9.Cu" signal "L10")
		(22 "In10.Cu" signal "L11GND")
		(24 "In11.Cu" signal "L12")
		(26 "In12.Cu" signal "L13GND")
		(2 "B.Cu" signal "BOTTOM")
		(9 "F.Adhes" user "F.Adhesive")
		(11 "B.Adhes" user "B.Adhesive")
		(13 "F.Paste" user "Package Geometry/Pastemask Top")
		(15 "B.Paste" user "Package Geometry/Pastemask Bottom")
		(5 "F.SilkS" user "Ref Des/Silkscreen Top")
		(7 "B.SilkS" user "Ref Des/Silkscreen Bottom")
		(1 "F.Mask" user "Board Geometry/Soldermask Top")
		(3 "B.Mask" user "Board Geometry/Soldermask Bottom")
		(17 "Dwgs.User" user "User.Drawings")
		(19 "Cmts.User" user "User.Comments")
		(21 "Eco1.User" user "User.Eco1")
		(23 "Eco2.User" user "User.Eco2")
		(25 "Edge.Cuts" user "Board Geometry/Outline")
		(27 "Margin" user)
		(31 "F.CrtYd" user "Package Geometry/Place Bound Top")
		(29 "B.CrtYd" user "Package Geometry/Place Bound Bottom")
		(35 "F.Fab" user "Ref Des/Assembly Top")
		(33 "B.Fab" user "Ref Des/Assembly Bottom")
	)
	(footprint ""
		(layer "F.Cu")
		(at 396.875 -149.0472)
		(property "Reference" "R2L16"
			(at 0 0 0)
			(layer "F.SilkS")
			(hide yes)
			(effects
				(font
					(size 1.27 1.27)
				)
			)
		)
		(property "Value" ""
			(at 0 0 0)
			(layer "F.Fab")
			(effects
				(font
					(size 1.27 1.27)
				)
			)
		)
		(duplicate_pad_numbers_are_jumpers no)
		(fp_poly
			(pts
				(xy -0.2794 -0.1016) (xy 0.2794 -0.1016) (xy 0.2794 0.9906) (xy -0.2794 0.9906)
			)
			(stroke
				(width 0)
				(type default)
			)
			(fill no)
			(layer "F.CrtYd")
		)
		(fp_line
			(start -0.2794 -0.1016)
			(end -0.2794 0.9906)
			(stroke
				(width 0.1)
				(type default)
			)
			(layer "F.Fab")
		)
		(fp_line
			(start -0.2794 0.9906)
			(end 0.2794 0.9906)
			(stroke
				(width 0.1)
				(type default)
			)
			(layer "F.Fab")
		)
		(fp_line
			(start 0.2794 -0.1016)
			(end -0.2794 -0.1016)
			(stroke
				(width 0.1)
				(type default)
			)
			(layer "F.Fab")
		)
		(fp_line
			(start 0.2794 0.9906)
			(end 0.2794 -0.1016)
			(stroke
				(width 0.1)
				(type default)
			)
			(layer "F.Fab")
		)
		(pad "1" smd rect
			(at 0 0)
			(size 0.508 0.508)
			(layers "F.Cu" "F.Mask" "F.Paste")
			(net "PWRGD_PVNN_PCH_R")
		)
		(pad "2" smd rect
			(at 0 0.889)
			(size 0.508 0.508)
			(layers "F.Cu" "F.Mask" "F.Paste")
			(net "PWRGD_PVNN_P1V05_PCH")
		)
		(zone
			(layer "F.Cu")
			(hatch none 0.5)
			(connect_pads
				(clearance 0)
			)
			(min_thickness 0.25)
			(keepout
				(tracks allowed)
				(vias not_allowed)
				(pads allowed)
				(copperpour not_allowed)
				(footprints allowed)
			)
			(placement
				(enabled no)
				(sheetname "")
			)
			(fill
				(thermal_gap 0.5)
				(thermal_bridge_width 0.5)
				(island_removal_mode 0)
			)
			(polygon
				(pts
					(xy 396.621 -148.7932) (xy 397.129 -148.7932) (xy 397.129 -148.4122) (xy 396.621 -148.4122)
				)
			)
		)
		(zone
			(layer "F.Cu")
			(hatch none 0.5)
			(connect_pads
				(clearance 0)
			)
			(min_thickness 0.25)
			(keepout
				(tracks not_allowed)
				(vias allowed)
				(pads allowed)
				(copperpour not_allowed)
				(footprints allowed)
			)
			(placement
				(enabled no)
				(sheetname "")
			)
			(fill
				(thermal_gap 0.5)
				(thermal_bridge_width 0.5)
				(island_removal_mode 0)
			)
			(polygon
				(pts
					(xy 396.621 -148.4122) (xy 397.129 -148.4122) (xy 397.129 -148.7932) (xy 396.621 -148.7932)
				)
			)
		)
	)
	(footprint ""
		(layer "F.Cu")
		(at 2.4003 -114.554 -90)
		(property "Reference" "R10W7"
			(at -0.8382 -0.67818 270)
			(unlocked yes)
			(layer "F.SilkS")
			(effects
				(font
					(size 0.4064 0.254)
					(thickness 0.1524)
				)
				(justify left)
			)
		)
		(property "Value" ""
			(at 0 0 270)
			(layer "F.Fab")
			(effects
				(font
					(size 1.27 1.27)
				)
			)
		)
		(duplicate_pad_numbers_are_jumpers no)
		(fp_poly
			(pts
				(xy -0.2794 -0.1016) (xy 0.2794 -0.1016) (xy 0.2794 0.9906) (xy -0.2794 0.9906)
			)
			(stroke
				(width 0)
				(type default)
			)
			(fill no)
			(layer "F.CrtYd")
		)
		(fp_line
			(start -0.2794 0.9906)
			(end 0.2794 0.9906)
			(stroke
				(width 0.1)
				(type default)
			)
			(layer "F.Fab")
		)
		(fp_line
			(start 0.2794 0.9906)
			(end 0.2794 -0.1016)
			(stroke
				(width 0.1)
				(type default)
			)
			(layer "F.Fab")
		)
		(fp_line
			(start -0.2794 -0.1016)
			(end -0.2794 0.9906)
			(stroke
				(width 0.1)
				(type default)
			)
			(layer "F.Fab")
		)
		(fp_line
			(start 0.2794 -0.1016)
			(end -0.2794 -0.1016)
			(stroke
				(width 0.1)
				(type default)
			)
			(layer "F.Fab")
		)
		(pad "1" smd rect
			(at 0 0 270)
			(size 0.508 0.508)
			(layers "F.Cu" "F.Mask" "F.Paste")
			(net "P3V3_STBY")
		)
		(pad "2" smd rect
			(at 0 0.889 270)
			(size 0.508 0.508)
			(layers "F.Cu" "F.Mask" "F.Paste")
			(net "PUMP_TACH1")
		)
		(zone
			(layer "F.Cu")
			(hatch none 0.5)
			(connect_pads
				(clearance 0)
			)
			(min_thickness 0.25)
			(keepout
				(tracks not_allowed)
				(vias allowed)
				(pads allowed)
				(copperpour not_allowed)
				(footprints allowed)
			)
			(placement
				(enabled no)
				(sheetname "")
			)
			(fill
				(thermal_gap 0.5)
				(thermal_bridge_width 0.5)
				(island_removal_mode 0)
			)
			(polygon
				(pts
					(xy 1.7653 -114.808) (xy 1.7653 -114.3) (xy 2.1463 -114.3) (xy 2.1463 -114.808)
				)
			)
		)
		(zone
			(layer "F.Cu")
			(hatch none 0.5)
			(connect_pads
				(clearance 0)
			)
			(min_thickness 0.25)
			(keepout
				(tracks allowed)
				(vias not_allowed)
				(pads allowed)
				(copperpour not_allowed)
				(footprints allowed)
			)
			(placement
				(enabled no)
				(sheetname "")
			)
			(fill
				(thermal_gap 0.5)
				(thermal_bridge_width 0.5)
				(island_removal_mode 0)
			)
			(polygon
				(pts
					(xy 2.1463 -114.808) (xy 2.1463 -114.3) (xy 1.7653 -114.3) (xy 1.7653 -114.808)
				)
			)
		)
	)
	(footprint ""
		(layer "F.Cu")
		(at 475.2594 -148.9456 180)
		(property "Reference" "R9A9"
			(at 0 0 180)
			(layer "F.SilkS")
			(hide yes)
			(effects
				(font
					(size 1.27 1.27)
				)
			)
		)
		(property "Value" ""
			(at 0 0 180)
			(layer "F.Fab")
			(effects
				(font
					(size 1.27 1.27)
				)
			)
		)
		(duplicate_pad_numbers_are_jumpers no)
		(fp_poly
			(pts
				(xy -0.2794 -0.1016) (xy 0.2794 -0.1016) (xy 0.2794 0.9906) (xy -0.2794 0.9906)
			)
			(stroke
				(width 0)
				(type default)
			)
			(fill no)
			(layer "F.CrtYd")
		)
		(fp_line
			(start 0.2794 0.9906)
			(end 0.2794 -0.1016)
			(stroke
				(width 0.1)
				(type default)
			)
			(layer "F.Fab")
		)
		(fp_line
			(start 0.2794 -0.1016)
			(end -0.2794 -0.1016)
			(stroke
				(width 0.1)
				(type default)
			)
			(layer "F.Fab")
		)
		(fp_line
			(start -0.2794 0.9906)
			(end 0.2794 0.9906)
			(stroke
				(width 0.1)
				(type default)
			)
			(layer "F.Fab")
		)
		(fp_line
			(start -0.2794 -0.1016)
			(end -0.2794 0.9906)
			(stroke
				(width 0.1)
				(type default)
			)
			(layer "F.Fab")
		)
		(pad "1" smd rect
			(at 0 0 180)
			(size 0.508 0.508)
			(layers "F.Cu" "F.Mask" "F.Paste")
			(net "RST_SYSTEM_BTN_BUF_N")
		)
		(pad "2" smd rect
			(at 0 0.889 180)
			(size 0.508 0.508)
			(layers "F.Cu" "F.Mask" "F.Paste")
			(net "RST_SYSTEM_BTN_N")
		)
		(zone
			(layer "F.Cu")
			(hatch none 0.5)
			(connect_pads
				(clearance 0)
			)
			(min_thickness 0.25)
			(keepout
				(tracks not_allowed)
				(vias allowed)
				(pads allowed)
				(copperpour not_allowed)
				(footprints allowed)
			)
			(placement
				(enabled no)
				(sheetname "")
			)
			(fill
				(thermal_gap 0.5)
				(thermal_bridge_width 0.5)
				(island_removal_mode 0)
			)
			(polygon
				(pts
					(xy 475.5134 -149.5806) (xy 475.0054 -149.5806) (xy 475.0054 -149.1996) (xy 475.5134 -149.1996)
				)
			)
		)
		(zone
			(layer "F.Cu")
			(hatch none 0.5)
			(connect_pads
				(clearance 0)
			)
			(min_thickness 0.25)
			(keepout
				(tracks allowed)
				(vias not_allowed)
				(pads allowed)
				(copperpour not_allowed)
				(footprints allowed)
			)
			(placement
				(enabled no)
				(sheetname "")
			)
			(fill
				(thermal_gap 0.5)
				(thermal_bridge_width 0.5)
				(island_removal_mode 0)
			)
			(polygon
				(pts
					(xy 475.5134 -149.1996) (xy 475.0054 -149.1996) (xy 475.0054 -149.5806) (xy 475.5134 -149.5806)
				)
			)
		)
	)
)
